# BASEBOARD_FAB2 (Tioga Pass) — schematic netlist excerpt (pin names and nets, part order shuffled) for the footprints in the layout excerpt that follows; sources: Cadence DE-HDL packaged netlist, KiCad conversion of Wiwynn_Tioga_Pass_MB.brd

R1W3  1MR2F-L-GP  1%  pkg SMD-RG1  page 250 : \1\ = P3V3_STBY ; \2\ = FM_OCP_MEZZB_PRES_N
R1W45  RES  4.75K 1% CHIP  pkg 0402  page 188 : A = P3V3_STBY ; B = FM_GBE3_LVC3_MOD_ABS
C8P19  CAP  47UF 4V 20% X6S  pkg 0805  page 76 : A = PVCCIN_CPU1 ; B = GND

(kicad_pcb
	(version 20260206)
	(generator "pcbnew")
	(generator_version "10.0")
	(general
		(thickness 1.6)
		(legacy_teardrops no)
	)
	(paper "A4")
	(title_block
		(title "Wiwynn_Tioga_Pass_MB.brd")
		(comment 1 "Tioga Pass / footprints 3688-3690 of 4770")
	)
	(layers
		(0 "F.Cu" signal "TOP")
		(4 "In1.Cu" signal "L2GND")
		(6 "In2.Cu" signal "L3")
		(8 "In3.Cu" signal "L4GND")
		(10 "In4.Cu" signal "L5")
		(12 "In5.Cu" signal "L6GND")
		(14 "In6.Cu" signal "L7VCC")
		(16 "In7.Cu" signal "L8VCC")
		(18 "In8.Cu" signal "L9GND")
		(20 "In9.Cu" signal "L10")
		(22 "In10.Cu" signal "L11GND")
		(24 "In11.Cu" signal "L12")
		(26 "In12.Cu" signal "L13GND")
		(2 "B.Cu" signal "BOTTOM")
		(9 "F.Adhes" user "F.Adhesive")
		(11 "B.Adhes" user "B.Adhesive")
		(13 "F.Paste" user "Package Geometry/Pastemask Top")
		(15 "B.Paste" user "Package Geometry/Pastemask Bottom")
		(5 "F.SilkS" user "Ref Des/Silkscreen Top")
		(7 "B.SilkS" user "Ref Des/Silkscreen Bottom")
		(1 "F.Mask" user "Board Geometry/Soldermask Top")
		(3 "B.Mask" user "Board Geometry/Soldermask Bottom")
		(17 "Dwgs.User" user "User.Drawings")
		(19 "Cmts.User" user "User.Comments")
		(21 "Eco1.User" user "User.Eco1")
		(23 "Eco2.User" user "User.Eco2")
		(25 "Edge.Cuts" user "Board Geometry/Outline")
		(27 "Margin" user)
		(31 "F.CrtYd" user "Package Geometry/Place Bound Top")
		(29 "B.CrtYd" user "Package Geometry/Place Bound Bottom")
		(35 "F.Fab" user "Ref Des/Assembly Top")
		(33 "B.Fab" user "Ref Des/Assembly Bottom")
	)
	(footprint ""
		(layer "B.Cu")
		(at 405.84882 -52.19192 90)
		(property "Reference" "R1W3"
			(at 0 0 90)
			(layer "B.SilkS")
			(hide yes)
			(effects
				(font
					(size 1.27 1.27)
				)
				(justify mirror)
			)
		)
		(property "Value" "*"
			(at -0.064008 -4.108196 90)
			(unlocked yes)
			(layer "B.Fab")
			(hide yes)
			(effects
				(font
					(size 1.27 1.016)
					(thickness 0.1524)
				)
				(justify mirror)
			)
		)
		(property "Device Type" "1MR2F-L-GP_SMD-RG1-1MR2F-L-GP,A"
			(at -0.064008 -5.632196 90)
			(unlocked yes)
			(layer "B.Fab")
			(hide yes)
			(effects
				(font
					(size 1.27 1.016)
					(thickness 0.1524)
				)
				(justify mirror)
			)
		)
		(duplicate_pad_numbers_are_jumpers no)
		(fp_line
			(start 0.508 -0.9398)
			(end 0.508 0.9398)
			(stroke
				(width 0.1524)
				(type default)
			)
			(layer "B.SilkS")
		)
		(fp_line
			(start -0.508 -0.9398)
			(end 0.508 -0.9398)
			(stroke
				(width 0.1524)
				(type default)
			)
			(layer "B.SilkS")
		)
		(fp_rect
			(start 0.508 0.9398)
			(end -0.508 -0.9398)
			(stroke
				(width 0)
				(type default)
			)
			(fill no)
			(layer "B.CrtYd")
		)
		(fp_rect
			(start 0.508 0.9398)
			(end -0.508 -0.9398)
			(stroke
				(width 0)
				(type default)
			)
			(fill no)
			(layer "B.Fab")
		)
		(pad "1" smd custom
			(at 0 -0.4445 270)
			(size 0.1397 0.1397)
			(layers "B.Cu" "B.Mask" "B.Paste")
			(net "P3V3_STBY")
			(options
				(clearance outline)
				(anchor circle)
			)
			(primitives
				(gr_poly
					(pts
						(arc
							(start -0.1778 0.2794)
							(mid -0.249642 0.249642)
							(end -0.2794 0.1778)
						)
						(arc
							(start -0.2794 -0.1778)
							(mid -0.249642 -0.249642)
							(end -0.1778 -0.2794)
						)
						(arc
							(start 0.1778 -0.2794)
							(mid 0.249642 -0.249642)
							(end 0.2794 -0.1778)
						)
						(arc
							(start 0.2794 0.1778)
							(mid 0.249642 0.249642)
							(end 0.1778 0.2794)
						)
					)
					(width 0)
					(fill yes)
				)
			)
		)
		(pad "2" smd custom
			(at 0 0.4445 270)
			(size 0.1397 0.1397)
			(layers "B.Cu" "B.Mask" "B.Paste")
			(net "FM_OCP_MEZZB_PRES_N")
			(options
				(clearance outline)
				(anchor circle)
			)
			(primitives
				(gr_poly
					(pts
						(arc
							(start -0.1778 0.2794)
							(mid -0.249642 0.249642)
							(end -0.2794 0.1778)
						)
						(arc
							(start -0.2794 -0.1778)
							(mid -0.249642 -0.249642)
							(end -0.1778 -0.2794)
						)
						(arc
							(start 0.1778 -0.2794)
							(mid 0.249642 -0.249642)
							(end 0.2794 -0.1778)
						)
						(arc
							(start 0.2794 0.1778)
							(mid 0.249642 0.249642)
							(end 0.1778 0.2794)
						)
					)
					(width 0)
					(fill yes)
				)
			)
		)
	)
	(footprint ""
		(layer "B.Cu")
		(at 470.027 -58.674 -90)
		(property "Reference" "R1W45"
			(at 0.8382 -0.67818 270)
			(unlocked yes)
			(layer "B.SilkS")
			(effects
				(font
					(size 0.4064 0.254)
					(thickness 0.1524)
				)
				(justify left mirror)
			)
		)
		(property "Value" ""
			(at 0 0 90)
			(layer "B.Fab")
			(effects
				(font
					(size 1.27 1.27)
				)
				(justify mirror)
			)
		)
		(duplicate_pad_numbers_are_jumpers no)
		(fp_poly
			(pts
				(xy 0.2794 -0.1016) (xy -0.2794 -0.1016) (xy -0.2794 0.9906) (xy 0.2794 0.9906)
			)
			(stroke
				(width 0)
				(type default)
			)
			(fill no)
			(layer "B.CrtYd")
		)
		(fp_line
			(start -0.2794 0.9906)
			(end -0.2794 -0.1016)
			(stroke
				(width 0.1)
				(type default)
			)
			(layer "B.Fab")
		)
		(fp_line
			(start 0.2794 0.9906)
			(end -0.2794 0.9906)
			(stroke
				(width 0.1)
				(type default)
			)
			(layer "B.Fab")
		)
		(fp_line
			(start -0.2794 -0.1016)
			(end 0.2794 -0.1016)
			(stroke
				(width 0.1)
				(type default)
			)
			(layer "B.Fab")
		)
		(fp_line
			(start 0.2794 -0.1016)
			(end 0.2794 0.9906)
			(stroke
				(width 0.1)
				(type default)
			)
			(layer "B.Fab")
		)
		(pad "1" smd rect
			(at 0 0 90)
			(size 0.508 0.508)
			(layers "B.Cu" "B.Mask" "B.Paste")
			(net "P3V3_STBY")
		)
		(pad "2" smd rect
			(at 0 0.889 90)
			(size 0.508 0.508)
			(layers "B.Cu" "B.Mask" "B.Paste")
			(net "FM_GBE3_LVC3_MOD_ABS")
		)
		(zone
			(layer "B.Cu")
			(hatch none 0.5)
			(connect_pads
				(clearance 0)
			)
			(min_thickness 0.25)
			(keepout
				(tracks not_allowed)
				(vias allowed)
				(pads allowed)
				(copperpour not_allowed)
				(footprints allowed)
			)
			(placement
				(enabled no)
				(sheetname "")
			)
			(fill
				(thermal_gap 0.5)
				(thermal_bridge_width 0.5)
				(island_removal_mode 0)
			)
			(polygon
				(pts
					(xy 469.392 -58.42) (xy 469.392 -58.928) (xy 469.773 -58.928) (xy 469.773 -58.42)
				)
			)
		)
		(zone
			(layer "B.Cu")
			(hatch none 0.5)
			(connect_pads
				(clearance 0)
			)
			(min_thickness 0.25)
			(keepout
				(tracks allowed)
				(vias not_allowed)
				(pads allowed)
				(copperpour not_allowed)
				(footprints allowed)
			)
			(placement
				(enabled no)
				(sheetname "")
			)
			(fill
				(thermal_gap 0.5)
				(thermal_bridge_width 0.5)
				(island_removal_mode 0)
			)
			(polygon
				(pts
					(xy 469.773 -58.42) (xy 469.773 -58.928) (xy 469.392 -58.928) (xy 469.392 -58.42)
				)
			)
		)
	)
	(footprint ""
		(layer "B.Cu")
		(at 97.206054 -77.82814)
		(property "Reference" "C8P19"
			(at 0 0 0)
			(layer "B.SilkS")
			(hide yes)
			(effects
				(font
					(size 1.27 1.27)
				)
				(justify mirror)
			)
		)
		(property "Value" ""
			(at 0 0 0)
			(layer "B.Fab")
			(effects
				(font
					(size 1.27 1.27)
				)
				(justify mirror)
			)
		)
		(duplicate_pad_numbers_are_jumpers no)
		(fp_poly
			(pts
				(xy 0.7239 -0.2159) (xy -0.7239 -0.2159) (xy -0.7239 1.9939) (xy 0.7239 1.9939)
			)
			(stroke
				(width 0)
				(type default)
			)
			(fill no)
			(layer "B.CrtYd")
		)
		(fp_line
			(start -0.7239 -0.2159)
			(end 0.7239 -0.2159)
			(stroke
				(width 0.1)
				(type default)
			)
			(layer "B.Fab")
		)
		(fp_line
			(start -0.7239 1.9939)
			(end -0.7239 -0.2159)
			(stroke
				(width 0.1)
				(type default)
			)
			(layer "B.Fab")
		)
		(fp_line
			(start 0.7239 -0.2159)
			(end 0.7239 1.9939)
			(stroke
				(width 0.1)
				(type default)
			)
			(layer "B.Fab")
		)
		(fp_line
			(start 0.7239 1.9939)
			(end -0.7239 1.9939)
			(stroke
				(width 0.1)
				(type default)
			)
			(layer "B.Fab")
		)
		(pad "1" smd rect
			(at 0 0 180)
			(size 1.27 1.016)
			(layers "B.Cu" "B.Mask" "B.Paste")
			(net "PVCCIN_CPU1")
		)
		(pad "2" smd rect
			(at 0 1.778 180)
			(size 1.27 1.016)
			(layers "B.Cu" "B.Mask" "B.Paste")
			(net "GND")
		)
		(zone
			(layer "B.Cu")
			(hatch none 0.5)
			(connect_pads
				(clearance 0)
			)
			(min_thickness 0.25)
			(keepout
				(tracks not_allowed)
				(vias allowed)
				(pads allowed)
				(copperpour not_allowed)
				(footprints allowed)
			)
			(placement
				(enabled no)
				(sheetname "")
			)
			(fill
				(thermal_gap 0.5)
				(thermal_bridge_width 0.5)
				(island_removal_mode 0)
			)
			(polygon
				(pts
					(xy 97.841054 -77.32014) (xy 96.571054 -77.32014) (xy 96.571054 -76.55814) (xy 97.841054 -76.55814)
				)
			)
		)
	)
)
